(kicad_pcb
	(version 20260206)
	(generator "pcbnew")
	(generator_version "10.0")
	(general
		(thickness 1.6)
		(legacy_teardrops no)
	)
	(paper "A4")
	(title_block
		(title "Wiwynn_Tioga_Pass_MB.brd")
		(comment 1 "Tioga Pass / footprints 4461-4467 of 4770")
	)
	(layers
		(0 "F.Cu" signal "TOP")
		(4 "In1.Cu" signal "L2GND")
		(6 "In2.Cu" signal "L3")
		(8 "In3.Cu" signal "L4GND")
		(10 "In4.Cu" signal "L5")
		(12 "In5.Cu" signal "L6GND")
		(14 "In6.Cu" signal "L7VCC")
		(16 "In7.Cu" signal "L8VCC")
		(18 "In8.Cu" signal "L9GND")
		(20 "In9.Cu" signal "L10")
		(22 "In10.Cu" signal "L11GND")
		(24 "In11.Cu" signal "L12")
		(26 "In12.Cu" signal "L13GND")
		(2 "B.Cu" signal "BOTTOM")
		(9 "F.Adhes" user "F.Adhesive")
		(11 "B.Adhes" user "B.Adhesive")
		(13 "F.Paste" user "Package Geometry/Pastemask Top")
		(15 "B.Paste" user "Package Geometry/Pastemask Bottom")
		(5 "F.SilkS" user "Ref Des/Silkscreen Top")
		(7 "B.SilkS" user "Ref Des/Silkscreen Bottom")
		(1 "F.Mask" user "Board Geometry/Soldermask Top")
		(3 "B.Mask" user "Board Geometry/Soldermask Bottom")
		(17 "Dwgs.User" user "User.Drawings")
		(19 "Cmts.User" user "User.Comments")
		(21 "Eco1.User" user "User.Eco1")
		(23 "Eco2.User" user "User.Eco2")
		(25 "Edge.Cuts" user "Board Geometry/Outline")
		(27 "Margin" user)
		(31 "F.CrtYd" user "Package Geometry/Place Bound Top")
		(29 "B.CrtYd" user "Package Geometry/Place Bound Bottom")
		(35 "F.Fab" user "Ref Des/Assembly Top")
		(33 "B.Fab" user "Ref Des/Assembly Bottom")
	)
	(footprint ""
		(layer "B.Cu")
		(at 471.424 -116.84 180)
		(property "Reference" "R1M17"
			(at 0 0 0)
			(layer "B.SilkS")
			(hide yes)
			(effects
				(font
					(size 1.27 1.27)
				)
				(justify mirror)
			)
		)
		(property "Value" ""
			(at 0 0 0)
			(layer "B.Fab")
			(effects
				(font
					(size 1.27 1.27)
				)
				(justify mirror)
			)
		)
		(duplicate_pad_numbers_are_jumpers no)
		(fp_poly
			(pts
				(xy 0.2794 -0.1016) (xy -0.2794 -0.1016) (xy -0.2794 0.9906) (xy 0.2794 0.9906)
			)
			(stroke
				(width 0)
				(type default)
			)
			(fill no)
			(layer "B.CrtYd")
		)
		(fp_line
			(start 0.2794 0.9906)
			(end -0.2794 0.9906)
			(stroke
				(width 0.1)
				(type default)
			)
			(layer "B.Fab")
		)
		(fp_line
			(start 0.2794 -0.1016)
			(end 0.2794 0.9906)
			(stroke
				(width 0.1)
				(type default)
			)
			(layer "B.Fab")
		)
		(fp_line
			(start -0.2794 0.9906)
			(end -0.2794 -0.1016)
			(stroke
				(width 0.1)
				(type default)
			)
			(layer "B.Fab")
		)
		(fp_line
			(start -0.2794 -0.1016)
			(end 0.2794 -0.1016)
			(stroke
				(width 0.1)
				(type default)
			)
			(layer "B.Fab")
		)
		(pad "1" smd rect
			(at 0 0)
			(size 0.508 0.508)
			(layers "B.Cu" "B.Mask" "B.Paste")
			(net "RMII_BMC_OCP_RXD0")
		)
		(pad "2" smd rect
			(at 0 0.889)
			(size 0.508 0.508)
			(layers "B.Cu" "B.Mask" "B.Paste")
			(net "RMII_BMC_OCP_RXD0_R")
		)
		(zone
			(layer "B.Cu")
			(hatch none 0.5)
			(connect_pads
				(clearance 0)
			)
			(min_thickness 0.25)
			(keepout
				(tracks not_allowed)
				(vias allowed)
				(pads allowed)
				(copperpour not_allowed)
				(footprints allowed)
			)
			(placement
				(enabled no)
				(sheetname "")
			)
			(fill
				(thermal_gap 0.5)
				(thermal_bridge_width 0.5)
				(island_removal_mode 0)
			)
			(polygon
				(pts
					(xy 471.17 -117.475) (xy 471.678 -117.475) (xy 471.678 -117.094) (xy 471.17 -117.094)
				)
			)
		)
		(zone
			(layer "B.Cu")
			(hatch none 0.5)
			(connect_pads
				(clearance 0)
			)
			(min_thickness 0.25)
			(keepout
				(tracks allowed)
				(vias not_allowed)
				(pads allowed)
				(copperpour not_allowed)
				(footprints allowed)
			)
			(placement
				(enabled no)
				(sheetname "")
			)
			(fill
				(thermal_gap 0.5)
				(thermal_bridge_width 0.5)
				(island_removal_mode 0)
			)
			(polygon
				(pts
					(xy 471.17 -117.094) (xy 471.678 -117.094) (xy 471.678 -117.475) (xy 471.17 -117.475)
				)
			)
		)
	)
	(footprint ""
		(layer "B.Cu")
		(at 416.179 -22.987 180)
		(property "Reference" "C25W73"
			(at 0.8382 -0.67818 180)
			(unlocked yes)
			(layer "B.SilkS")
			(effects
				(font
					(size 0.4064 0.254)
					(thickness 0.1524)
				)
				(justify left mirror)
			)
		)
		(property "Value" ""
			(at 0 0 0)
			(layer "B.Fab")
			(effects
				(font
					(size 1.27 1.27)
				)
				(justify mirror)
			)
		)
		(duplicate_pad_numbers_are_jumpers no)
		(fp_poly
			(pts
				(xy -0.3048 -0.1016) (xy -0.3048 0.9906) (xy 0.3048 0.9906) (xy 0.3048 -0.1016)
			)
			(stroke
				(width 0)
				(type default)
			)
			(fill no)
			(layer "B.CrtYd")
		)
		(fp_line
			(start 0.3048 0.9906)
			(end -0.3048 0.9906)
			(stroke
				(width 0.1)
				(type default)
			)
			(layer "B.Fab")
		)
		(fp_line
			(start 0.3048 -0.1016)
			(end 0.3048 0.9906)
			(stroke
				(width 0.1)
				(type default)
			)
			(layer "B.Fab")
		)
		(fp_line
			(start -0.3048 0.9906)
			(end -0.3048 -0.1016)
			(stroke
				(width 0.1)
				(type default)
			)
			(layer "B.Fab")
		)
		(fp_line
			(start -0.3048 -0.1016)
			(end 0.3048 -0.1016)
			(stroke
				(width 0.1)
				(type default)
			)
			(layer "B.Fab")
		)
		(pad "1" smd rect
			(at 0 0)
			(size 0.508 0.508)
			(layers "B.Cu" "B.Mask" "B.Paste")
			(net "BMC_VGA_GREEN")
		)
		(pad "2" smd rect
			(at 0 0.889)
			(size 0.508 0.508)
			(layers "B.Cu" "B.Mask" "B.Paste")
			(net "GND")
		)
		(zone
			(layer "B.Cu")
			(hatch none 0.5)
			(connect_pads
				(clearance 0)
			)
			(min_thickness 0.25)
			(keepout
				(tracks not_allowed)
				(vias allowed)
				(pads allowed)
				(copperpour not_allowed)
				(footprints allowed)
			)
			(placement
				(enabled no)
				(sheetname "")
			)
			(fill
				(thermal_gap 0.5)
				(thermal_bridge_width 0.5)
				(island_removal_mode 0)
			)
			(polygon
				(pts
					(xy 415.925 -23.622) (xy 416.433 -23.622) (xy 416.433 -23.241) (xy 415.925 -23.241)
				)
			)
		)
		(zone
			(layer "B.Cu")
			(hatch none 0.5)
			(connect_pads
				(clearance 0)
			)
			(min_thickness 0.25)
			(keepout
				(tracks allowed)
				(vias not_allowed)
				(pads allowed)
				(copperpour not_allowed)
				(footprints allowed)
			)
			(placement
				(enabled no)
				(sheetname "")
			)
			(fill
				(thermal_gap 0.5)
				(thermal_bridge_width 0.5)
				(island_removal_mode 0)
			)
			(polygon
				(pts
					(xy 415.925 -23.241) (xy 416.433 -23.241) (xy 416.433 -23.622) (xy 415.925 -23.622)
				)
			)
		)
	)
	(footprint ""
		(layer "B.Cu")
		(at 407.3652 -13.0683 180)
		(property "Reference" "R8F24"
			(at 0 0 0)
			(layer "B.SilkS")
			(hide yes)
			(effects
				(font
					(size 1.27 1.27)
				)
				(justify mirror)
			)
		)
		(property "Value" ""
			(at 0 0 0)
			(layer "B.Fab")
			(effects
				(font
					(size 1.27 1.27)
				)
				(justify mirror)
			)
		)
		(duplicate_pad_numbers_are_jumpers no)
		(fp_poly
			(pts
				(xy 0.2794 -0.1016) (xy -0.2794 -0.1016) (xy -0.2794 0.9906) (xy 0.2794 0.9906)
			)
			(stroke
				(width 0)
				(type default)
			)
			(fill no)
			(layer "B.CrtYd")
		)
		(fp_line
			(start 0.2794 0.9906)
			(end -0.2794 0.9906)
			(stroke
				(width 0.1)
				(type default)
			)
			(layer "B.Fab")
		)
		(fp_line
			(start 0.2794 -0.1016)
			(end 0.2794 0.9906)
			(stroke
				(width 0.1)
				(type default)
			)
			(layer "B.Fab")
		)
		(fp_line
			(start -0.2794 0.9906)
			(end -0.2794 -0.1016)
			(stroke
				(width 0.1)
				(type default)
			)
			(layer "B.Fab")
		)
		(fp_line
			(start -0.2794 -0.1016)
			(end 0.2794 -0.1016)
			(stroke
				(width 0.1)
				(type default)
			)
			(layer "B.Fab")
		)
		(pad "1" smd rect
			(at 0 0)
			(size 0.508 0.508)
			(layers "B.Cu" "B.Mask" "B.Paste")
			(net "P3V3_STBY")
		)
		(pad "2" smd rect
			(at 0 0.889)
			(size 0.508 0.508)
			(layers "B.Cu" "B.Mask" "B.Paste")
			(net "FP_NMI_BTN_N")
		)
		(zone
			(layer "B.Cu")
			(hatch none 0.5)
			(connect_pads
				(clearance 0)
			)
			(min_thickness 0.25)
			(keepout
				(tracks not_allowed)
				(vias allowed)
				(pads allowed)
				(copperpour not_allowed)
				(footprints allowed)
			)
			(placement
				(enabled no)
				(sheetname "")
			)
			(fill
				(thermal_gap 0.5)
				(thermal_bridge_width 0.5)
				(island_removal_mode 0)
			)
			(polygon
				(pts
					(xy 407.1112 -13.7033) (xy 407.6192 -13.7033) (xy 407.6192 -13.3223) (xy 407.1112 -13.3223)
				)
			)
		)
		(zone
			(layer "B.Cu")
			(hatch none 0.5)
			(connect_pads
				(clearance 0)
			)
			(min_thickness 0.25)
			(keepout
				(tracks allowed)
				(vias not_allowed)
				(pads allowed)
				(copperpour not_allowed)
				(footprints allowed)
			)
			(placement
				(enabled no)
				(sheetname "")
			)
			(fill
				(thermal_gap 0.5)
				(thermal_bridge_width 0.5)
				(island_removal_mode 0)
			)
			(polygon
				(pts
					(xy 407.1112 -13.3223) (xy 407.6192 -13.3223) (xy 407.6192 -13.7033) (xy 407.1112 -13.7033)
				)
			)
		)
	)
	(footprint ""
		(layer "B.Cu")
		(at 197.239128 -70.787006 90)
		(property "Reference" "R6P19"
			(at 0 0 90)
			(layer "B.SilkS")
			(hide yes)
			(effects
				(font
					(size 1.27 1.27)
				)
				(justify mirror)
			)
		)
		(property "Value" ""
			(at 0 0 90)
			(layer "B.Fab")
			(effects
				(font
					(size 1.27 1.27)
				)
				(justify mirror)
			)
		)
		(duplicate_pad_numbers_are_jumpers no)
		(fp_rect
			(start 0.2794 -0.1016)
			(end -0.2794 0.9906)
			(stroke
				(width 0)
				(type default)
			)
			(fill no)
			(layer "B.CrtYd")
		)
		(fp_line
			(start 0.2794 -0.1016)
			(end 0.2794 0.9906)
			(stroke
				(width 0.1)
				(type default)
			)
			(layer "B.Fab")
		)
		(fp_line
			(start -0.2794 -0.1016)
			(end 0.2794 -0.1016)
			(stroke
				(width 0.1)
				(type default)
			)
			(layer "B.Fab")
		)
		(fp_line
			(start 0.2794 0.9906)
			(end -0.2794 0.9906)
			(stroke
				(width 0.1)
				(type default)
			)
			(layer "B.Fab")
		)
		(fp_line
			(start -0.2794 0.9906)
			(end -0.2794 -0.1016)
			(stroke
				(width 0.1)
				(type default)
			)
			(layer "B.Fab")
		)
		(pad "1" smd rect
			(at 0 0 270)
			(size 0.508 0.508)
			(layers "B.Cu" "B.Mask" "B.Paste")
			(net "VR_PVCCIN_CPU0_PH3_VCIN")
		)
		(pad "2" smd rect
			(at 0 0.889 270)
			(size 0.508 0.508)
			(layers "B.Cu" "B.Mask" "B.Paste")
			(net "P5V_STBY")
		)
		(zone
			(layer "B.Cu")
			(hatch none 0.5)
			(connect_pads
				(clearance 0)
			)
			(min_thickness 0.25)
			(keepout
				(tracks not_allowed)
				(vias allowed)
				(pads allowed)
				(copperpour not_allowed)
				(footprints allowed)
			)
			(placement
				(enabled no)
				(sheetname "")
			)
			(fill
				(thermal_gap 0.5)
				(thermal_bridge_width 0.5)
				(island_removal_mode 0)
			)
			(polygon
				(pts
					(xy 197.493128 -71.041006) (xy 197.493128 -70.533006) (xy 197.874128 -70.533006) (xy 197.874128 -71.041006)
				)
			)
		)
		(zone
			(layer "B.Cu")
			(hatch none 0.5)
			(connect_pads
				(clearance 0)
			)
			(min_thickness 0.25)
			(keepout
				(tracks allowed)
				(vias not_allowed)
				(pads allowed)
				(copperpour not_allowed)
				(footprints allowed)
			)
			(placement
				(enabled no)
				(sheetname "")
			)
			(fill
				(thermal_gap 0.5)
				(thermal_bridge_width 0.5)
				(island_removal_mode 0)
			)
			(polygon
				(pts
					(xy 197.493128 -71.041006) (xy 197.493128 -70.533006) (xy 197.874128 -70.533006) (xy 197.874128 -71.041006)
				)
			)
		)
	)
	(footprint ""
		(layer "B.Cu")
		(at 382.473708 -104.314244 -90)
		(property "Reference" "R3N2"
			(at 0 0 90)
			(layer "B.SilkS")
			(hide yes)
			(effects
				(font
					(size 1.27 1.27)
				)
				(justify mirror)
			)
		)
		(property "Value" ""
			(at 0 0 90)
			(layer "B.Fab")
			(effects
				(font
					(size 1.27 1.27)
				)
				(justify mirror)
			)
		)
		(duplicate_pad_numbers_are_jumpers no)
		(fp_poly
			(pts
				(xy 0.2794 -0.1016) (xy -0.2794 -0.1016) (xy -0.2794 0.9906) (xy 0.2794 0.9906)
			)
			(stroke
				(width 0)
				(type default)
			)
			(fill no)
			(layer "B.CrtYd")
		)
		(fp_line
			(start -0.2794 0.9906)
			(end -0.2794 -0.1016)
			(stroke
				(width 0.1)
				(type default)
			)
			(layer "B.Fab")
		)
		(fp_line
			(start 0.2794 0.9906)
			(end -0.2794 0.9906)
			(stroke
				(width 0.1)
				(type default)
			)
			(layer "B.Fab")
		)
		(fp_line
			(start -0.2794 -0.1016)
			(end 0.2794 -0.1016)
			(stroke
				(width 0.1)
				(type default)
			)
			(layer "B.Fab")
		)
		(fp_line
			(start 0.2794 -0.1016)
			(end 0.2794 0.9906)
			(stroke
				(width 0.1)
				(type default)
			)
			(layer "B.Fab")
		)
		(pad "1" smd rect
			(at 0 0 90)
			(size 0.508 0.508)
			(layers "B.Cu" "B.Mask" "B.Paste")
			(net "P3V3_STBY")
		)
		(pad "2" smd rect
			(at 0 0.889 90)
			(size 0.508 0.508)
			(layers "B.Cu" "B.Mask" "B.Paste")
			(net "FM_FLASH_DESC_OVERRIDE")
		)
		(zone
			(layer "B.Cu")
			(hatch none 0.5)
			(connect_pads
				(clearance 0)
			)
			(min_thickness 0.25)
			(keepout
				(tracks not_allowed)
				(vias allowed)
				(pads allowed)
				(copperpour not_allowed)
				(footprints allowed)
			)
			(placement
				(enabled no)
				(sheetname "")
			)
			(fill
				(thermal_gap 0.5)
				(thermal_bridge_width 0.5)
				(island_removal_mode 0)
			)
			(polygon
				(pts
					(xy 381.838708 -104.060244) (xy 381.838708 -104.568244) (xy 382.219708 -104.568244) (xy 382.219708 -104.060244)
				)
			)
		)
		(zone
			(layer "B.Cu")
			(hatch none 0.5)
			(connect_pads
				(clearance 0)
			)
			(min_thickness 0.25)
			(keepout
				(tracks allowed)
				(vias not_allowed)
				(pads allowed)
				(copperpour not_allowed)
				(footprints allowed)
			)
			(placement
				(enabled no)
				(sheetname "")
			)
			(fill
				(thermal_gap 0.5)
				(thermal_bridge_width 0.5)
				(island_removal_mode 0)
			)
			(polygon
				(pts
					(xy 382.219708 -104.060244) (xy 382.219708 -104.568244) (xy 381.838708 -104.568244) (xy 381.838708 -104.060244)
				)
			)
		)
	)
	(footprint ""
		(layer "B.Cu")
		(at 386.08 -48.006 90)
		(property "Reference" "R3T12"
			(at 0 0 90)
			(layer "B.SilkS")
			(hide yes)
			(effects
				(font
					(size 1.27 1.27)
				)
				(justify mirror)
			)
		)
		(property "Value" ""
			(at 0 0 90)
			(layer "B.Fab")
			(effects
				(font
					(size 1.27 1.27)
				)
				(justify mirror)
			)
		)
		(duplicate_pad_numbers_are_jumpers no)
		(fp_poly
			(pts
				(xy 0.2794 -0.1016) (xy -0.2794 -0.1016) (xy -0.2794 0.9906) (xy 0.2794 0.9906)
			)
			(stroke
				(width 0)
				(type default)
			)
			(fill no)
			(layer "B.CrtYd")
		)
		(fp_line
			(start 0.2794 -0.1016)
			(end 0.2794 0.9906)
			(stroke
				(width 0.1)
				(type default)
			)
			(layer "B.Fab")
		)
		(fp_line
			(start -0.2794 -0.1016)
			(end 0.2794 -0.1016)
			(stroke
				(width 0.1)
				(type default)
			)
			(layer "B.Fab")
		)
		(fp_line
			(start 0.2794 0.9906)
			(end -0.2794 0.9906)
			(stroke
				(width 0.1)
				(type default)
			)
			(layer "B.Fab")
		)
		(fp_line
			(start -0.2794 0.9906)
			(end -0.2794 -0.1016)
			(stroke
				(width 0.1)
				(type default)
			)
			(layer "B.Fab")
		)
		(pad "1" smd rect
			(at 0 0 270)
			(size 0.508 0.508)
			(layers "B.Cu" "B.Mask" "B.Paste")
			(net "P3V3_STBY")
		)
		(pad "2" smd rect
			(at 0 0.889 270)
			(size 0.508 0.508)
			(layers "B.Cu" "B.Mask" "B.Paste")
			(net "PU_BIOS_SPI_WP1_N")
		)
		(zone
			(layer "B.Cu")
			(hatch none 0.5)
			(connect_pads
				(clearance 0)
			)
			(min_thickness 0.25)
			(keepout
				(tracks allowed)
				(vias not_allowed)
				(pads allowed)
				(copperpour not_allowed)
				(footprints allowed)
			)
			(placement
				(enabled no)
				(sheetname "")
			)
			(fill
				(thermal_gap 0.5)
				(thermal_bridge_width 0.5)
				(island_removal_mode 0)
			)
			(polygon
				(pts
					(xy 386.334 -48.26) (xy 386.334 -47.752) (xy 386.715 -47.752) (xy 386.715 -48.26)
				)
			)
		)
		(zone
			(layer "B.Cu")
			(hatch none 0.5)
			(connect_pads
				(clearance 0)
			)
			(min_thickness 0.25)
			(keepout
				(tracks not_allowed)
				(vias allowed)
				(pads allowed)
				(copperpour not_allowed)
				(footprints allowed)
			)
			(placement
				(enabled no)
				(sheetname "")
			)
			(fill
				(thermal_gap 0.5)
				(thermal_bridge_width 0.5)
				(island_removal_mode 0)
			)
			(polygon
				(pts
					(xy 386.715 -48.26) (xy 386.715 -47.752) (xy 386.334 -47.752) (xy 386.334 -48.26)
				)
			)
		)
	)
	(footprint ""
		(layer "B.Cu")
		(at 449.96735 -52.407058)
		(property "Reference" "C1R10"
			(at 0 0 0)
			(layer "B.SilkS")
			(hide yes)
			(effects
				(font
					(size 1.27 1.27)
				)
				(justify mirror)
			)
		)
		(property "Value" ""
			(at 0 0 0)
			(layer "B.Fab")
			(effects
				(font
					(size 1.27 1.27)
				)
				(justify mirror)
			)
		)
		(duplicate_pad_numbers_are_jumpers no)
		(fp_poly
			(pts
				(xy -0.3048 -0.1016) (xy -0.3048 0.9906) (xy 0.3048 0.9906) (xy 0.3048 -0.1016)
			)
			(stroke
				(width 0)
				(type default)
			)
			(fill no)
			(layer "B.CrtYd")
		)
		(fp_line
			(start -0.3048 -0.1016)
			(end 0.3048 -0.1016)
			(stroke
				(width 0.1)
				(type default)
			)
			(layer "B.Fab")
		)
		(fp_line
			(start -0.3048 0.9906)
			(end -0.3048 -0.1016)
			(stroke
				(width 0.1)
				(type default)
			)
			(layer "B.Fab")
		)
		(fp_line
			(start 0.3048 -0.1016)
			(end 0.3048 0.9906)
			(stroke
				(width 0.1)
				(type default)
			)
			(layer "B.Fab")
		)
		(fp_line
			(start 0.3048 0.9906)
			(end -0.3048 0.9906)
			(stroke
				(width 0.1)
				(type default)
			)
			(layer "B.Fab")
		)
		(pad "1" smd rect
			(at 0 0 180)
			(size 0.508 0.508)
			(layers "B.Cu" "B.Mask" "B.Paste")
			(net "P3E_CPU0_PE3_OCP_TXP<4>")
		)
		(pad "2" smd rect
			(at 0 0.889 180)
			(size 0.508 0.508)
			(layers "B.Cu" "B.Mask" "B.Paste")
			(net "P3E_OCP_CPU0_PE3_C_TXP<4>")
		)
		(zone
			(layer "B.Cu")
			(hatch none 0.5)
			(connect_pads
				(clearance 0)
			)
			(min_thickness 0.25)
			(keepout
				(tracks allowed)
				(vias not_allowed)
				(pads allowed)
				(copperpour not_allowed)
				(footprints allowed)
			)
			(placement
				(enabled no)
				(sheetname "")
			)
			(fill
				(thermal_gap 0.5)
				(thermal_bridge_width 0.5)
				(island_removal_mode 0)
			)
			(polygon
				(pts
					(xy 450.22135 -52.153058) (xy 449.71335 -52.153058) (xy 449.71335 -51.772058) (xy 450.22135 -51.772058)
				)
			)
		)
		(zone
			(layer "B.Cu")
			(hatch none 0.5)
			(connect_pads
				(clearance 0)
			)
			(min_thickness 0.25)
			(keepout
				(tracks not_allowed)
				(vias allowed)
				(pads allowed)
				(copperpour not_allowed)
				(footprints allowed)
			)
			(placement
				(enabled no)
				(sheetname "")
			)
			(fill
				(thermal_gap 0.5)
				(thermal_bridge_width 0.5)
				(island_removal_mode 0)
			)
			(polygon
				(pts
					(xy 450.22135 -51.772058) (xy 449.71335 -51.772058) (xy 449.71335 -52.153058) (xy 450.22135 -52.153058)
				)
			)
		)
	)
)
